# S9S_MB_2U (Grand Teton) — schematic parts with pin connectivity, parts 1623–1623 of 6093; source: Cadence DE-HDL packaged netlist (pstxprt.dat, pstxnet.dat, pstchip.dat)

J30  SCONN288_ADR50017P087CC  SCONN288_ADR50017-P087CC IO  pkg DDR288S_1-1VXB  page 111
  1  VIN_BULK0  POWER  = P12V_S3_AUX_CPU1_NVDIMM
  2  RFU0  TRI  = TP_CHG_CPU1_DIMM2_FRU_0
  3  VIN_MGMT  POWER  = P3V3_AUX
  4  HSCL  IN  = I3C_SPD_DDREFGH_CPU1_LVC1_SCL_5
  5  HSDA  BI  = I3C_SPD_DDREFGH_CPU1_LVC1_SDA
  6  VSS0  POWER  = GND
  7  DQ0_A  BI  = M_G_CPU1_SA_DQ<0>
  8  VSS1  POWER  = GND
  9  DQ1_A  BI  = M_G_CPU1_SA_DQ<1>
  10  VSS2  POWER  = GND
  11  DQS0_A_T  BI  = M_G_CPU1_SA_DQS_DP<0>
  12  DQS0_A_C  BI  = M_G_CPU1_SA_DQS_DN<0>
  13  VSS3  POWER  = GND
  14  DQ4_A  BI  = M_G_CPU1_SA_DQ<4>
  15  VSS4  POWER  = GND
  16  DQ5_A  BI  = M_G_CPU1_SA_DQ<5>
  17  VSS5  POWER  = GND
  18  DQ8_A  BI  = M_G_CPU1_SA_DQ<8>
  19  VSS6  POWER  = GND
  20  DQ9_A  BI  = M_G_CPU1_SA_DQ<9>
  21  VSS7  POWER  = GND
  22  DQS1_A_T  BI  = M_G_CPU1_SA_DQS_DP<1>
  23  DQS1_A_C  BI  = M_G_CPU1_SA_DQS_DN<1>
  24  VSS8  POWER  = GND
  25  DQ12_A  BI  = M_G_CPU1_SA_DQ<12>
  26  VSS9  POWER  = GND
  27  DQ13_A  BI  = M_G_CPU1_SA_DQ<13>
  28  VSS10  POWER  = GND
  29  DQ16_A  BI  = M_G_CPU1_SA_DQ<16>
  30  VSS11  POWER  = GND
  31  DQ17_A  BI  = M_G_CPU1_SA_DQ<17>
  32  VSS12  POWER  = GND
  33  DQS2_A_T  BI  = M_G_CPU1_SA_DQS_DP<2>
  34  DQS2_A_C  BI  = M_G_CPU1_SA_DQS_DN<2>
  35  VSS13  POWER  = GND
  36  DQ20_A  BI  = M_G_CPU1_SA_DQ<20>
  37  VSS14  POWER  = GND
  38  DQ21_A  BI  = M_G_CPU1_SA_DQ<21>
  39  VSS15  POWER  = GND
  40  DQ24_A  BI  = M_G_CPU1_SA_DQ<24>
  41  VSS16  POWER  = GND
  42  DQ25_A  BI  = M_G_CPU1_SA_DQ<25>
  43  VSS17  POWER  = GND
  44  DQS3_A_T  BI  = M_G_CPU1_SA_DQS_DP<3>
  45  DQS3_A_C  BI  = M_G_CPU1_SA_DQS_DN<3>
  46  VSS18  POWER  = GND
  47  DQ28_A  BI  = M_G_CPU1_SA_DQ<28>
  48  VSS19  POWER  = GND
  49  DQ29_A  BI  = M_G_CPU1_SA_DQ<29>
  50  VSS20  POWER  = GND
  51  CB0_A  BI  = M_G_CPU1_SA_CB<0>
  52  VSS21  POWER  = GND
  53  CB1_A  BI  = M_G_CPU1_SA_CB<1>
  54  VSS22  POWER  = GND
  55  DQS4_A_T  BI  = M_G_CPU1_SA_DQS_DP<4>
  56  DQS4_A_C  BI  = M_G_CPU1_SA_DQS_DN<4>
  57  VSS23  POWER  = GND
  58  CB4_A  BI  = M_G_CPU1_SA_CB<4>
  59  VSS24  POWER  = GND
  60  CB5_A  BI  = M_G_CPU1_SA_CB<5>
  61  VSS25  POWER  = GND
  62  ALERT_N  OUT  = M_G_CPU1_ALERT_N
  63  VSS26  POWER  = GND
  64  CS0_A_N  IN  = M_G_CPU1_SA_CS_N<2>
  65  VSS27  POWER  = GND
  66  CA0_A  IN  = M_G_CPU1_SA_CA<0>
  67  VSS28  POWER  = GND
  68  CA2_A  IN  = M_G_CPU1_SA_CA<2>
  69  VSS29  POWER  = GND
  70  CA4_A  IN  = M_G_CPU1_SA_CA<4>
  71  VSS30  POWER  = GND
  72  CA6_A  IN  = M_G_CPU1_SA_CA<6>
  73  VSS31  POWER  = GND
  74  PAR_A  IN  = M_G_CPU1_SA_PAR
  75  VSS32  POWER  = GND
  76  CA0_B  IN  = M_G_CPU1_SB_CA<0>
  77  VSS33  POWER  = GND
  78  CA2_B  IN  = M_G_CPU1_SB_CA<2>
  79  VSS34  POWER  = GND
  80  CA4_B  IN  = M_G_CPU1_SB_CA<4>
  81  VSS35  POWER  = GND
  82  CA6_B  IN  = M_G_CPU1_SB_CA<6>
  83  VSS36  POWER  = GND
  84  CS0_B_N  IN  = M_G_CPU1_SB_CS_N<2>
  85  VSS37  POWER  = GND
  86  \lbd||rsp_a_n\  OUT  = M_G_CPU1_SA_RSP<1>
  87  \lbs||rsp_b_n\  OUT  = M_G_CPU1_SB_RSP<1>
  88  VSS38  POWER  = GND
  89  CB4_B  BI  = M_G_CPU1_SB_CB<4>
  90  VSS39  POWER  = GND
  91  CB5_B  BI  = M_G_CPU1_SB_CB<5>
  92  VSS40  POWER  = GND
  93  \dqs9_b_t||tdqs9_b_t||dbi4_b_n\  BI  = M_G_CPU1_SB_DQS_DP<9>
  94  \dqs9_b_c||tdqs9_b_c\  BI  = M_G_CPU1_SB_DQS_DN<9>
  95  VSS41  POWER  = GND
  96  CB0_B  BI  = M_G_CPU1_SB_CB<0>
  97  VSS42  POWER  = GND
  98  CB1_B  BI  = M_G_CPU1_SB_CB<1>
  99  VSS43  POWER  = GND
  100  DQ0_B  BI  = M_G_CPU1_SB_DQ<0>
  101  VSS44  POWER  = GND
  102  DQ1_B  BI  = M_G_CPU1_SB_DQ<1>
  103  VSS45  POWER  = GND
  104  DQS0_B_T  BI  = M_G_CPU1_SB_DQS_DP<0>
  105  DQS0_B_C  BI  = M_G_CPU1_SB_DQS_DN<0>
  106  VSS46  POWER  = GND
  107  DQ4_B  BI  = M_G_CPU1_SB_DQ<4>
  108  VSS47  POWER  = GND
  109  DQ5_B  BI  = M_G_CPU1_SB_DQ<5>
  110  VSS48  POWER  = GND
  111  DQ8_B  BI  = M_G_CPU1_SB_DQ<8>
  112  VSS49  POWER  = GND
  113  DQ9_B  BI  = M_G_CPU1_SB_DQ<9>
  114  VSS50  POWER  = GND
  115  DQS1_B_T  BI  = M_G_CPU1_SB_DQS_DP<1>
  116  DQS1_B_C  BI  = M_G_CPU1_SB_DQS_DN<1>
  117  VSS51  POWER  = GND
  118  DQ12_B  BI  = M_G_CPU1_SB_DQ<12>
  119  VSS52  POWER  = GND
  120  DQ13_B  BI  = M_G_CPU1_SB_DQ<13>
  121  VSS53  POWER  = GND
  122  DQ16_B  BI  = M_G_CPU1_SB_DQ<16>
  123  VSS54  POWER  = GND
  124  DQ17_B  BI  = M_G_CPU1_SB_DQ<17>
  125  VSS55  POWER  = GND
  126  DQS2_B_T  BI  = M_G_CPU1_SB_DQS_DP<2>
  127  DQS2_B_C  BI  = M_G_CPU1_SB_DQS_DN<2>
  128  VSS56  POWER  = GND
  129  DQ20_B  BI  = M_G_CPU1_SB_DQ<20>
  130  VSS57  POWER  = GND
  131  DQ21_B  BI  = M_G_CPU1_SB_DQ<21>
  132  VSS58  POWER  = GND
  133  DQ24_B  BI  = M_G_CPU1_SB_DQ<24>
  134  VSS59  POWER  = GND
  135  DQ25_B  BI  = M_G_CPU1_SB_DQ<25>
  136  VSS60  POWER  = GND
  137  DQS3_B_T  BI  = M_G_CPU1_SB_DQS_DP<3>
  138  DQS3_B_C  BI  = M_G_CPU1_SB_DQS_DN<3>
  139  VSS61  POWER  = GND
  140  DQ28_B  BI  = M_G_CPU1_SB_DQ<28>
  141  VSS62  POWER  = GND
  142  DQ29_B  BI  = M_G_CPU1_SB_DQ<29>
  143  VSS63  POWER  = GND
  144  RFU1  TRI  = TP_CHG_CPU1_DIMM2_FRU_1
  145  VIN_BULK1  POWER  = P12V_S3_AUX_CPU1_NVDIMM
  146  VIN_BULK2  POWER  = P12V_S3_AUX_CPU1_NVDIMM
  147  \pwr_good||fail_n\  BI  = PWRGD_CHG_CPU1_DIMM2
  148  HSA  IN  = PD_CHG_CPU1_DIMM2_SAA
  149  RFU2  TRI  = TP_CHG_CPU1_DIMM2_FRU_2
  150  RFU3  TRI  = TP_CHG_CPU1_DIMM2_FRU_3
  151  VSS64  POWER  = GND
  152  DQ2_A  BI  = M_G_CPU1_SA_DQ<2>
  153  VSS65  POWER  = GND
  154  DQ3_A  BI  = M_G_CPU1_SA_DQ<3>
  155  VSS66  POWER  = GND
  156  \dqs5_a_c||tdqs5_a_c||dqs5_a_t||tdqs5_a_t\  BI  = M_G_CPU1_SA_DQS_DN<5>
  157  \dqs5_a_t||tdqs5_a_t\  BI  = M_G_CPU1_SA_DQS_DP<5>
  158  VSS67  POWER  = GND
  159  DQ6_A  BI  = M_G_CPU1_SA_DQ<6>
  160  VSS68  POWER  = GND
  161  DQ7_A  BI  = M_G_CPU1_SA_DQ<7>
  162  VSS69  POWER  = GND
  163  DQ10_A  BI  = M_G_CPU1_SA_DQ<10>
  164  VSS70  POWER  = GND
  165  DQ11_A  BI  = M_G_CPU1_SA_DQ<11>
  166  VSS71  POWER  = GND
  167  \dqs6_a_c||tdqs6_a_c||dqs6_a_t||tdqs6_a_t\  BI  = M_G_CPU1_SA_DQS_DN<6>
  168  \dqs6_a_t||tdqs6_a_t\  BI  = M_G_CPU1_SA_DQS_DP<6>
  169  VSS72  POWER  = GND
  170  DQ14_A  BI  = M_G_CPU1_SA_DQ<14>
  171  VSS73  POWER  = GND
  172  DQ15_A  BI  = M_G_CPU1_SA_DQ<15>
  173  VSS74  POWER  = GND
  174  DQ18_A  BI  = M_G_CPU1_SA_DQ<18>
  175  VSS75  POWER  = GND
  176  DQ19_A  BI  = M_G_CPU1_SA_DQ<19>
  177  VSS76  POWER  = GND
  178  \dqs7_a_c||tdqs7_a_c\  BI  = M_G_CPU1_SA_DQS_DN<7>
  179  \dqs7_a_t||tdqs7_a_t\  BI  = M_G_CPU1_SA_DQS_DP<7>
  180  VSS77  POWER  = GND
  181  DQ22_A  BI  = M_G_CPU1_SA_DQ<22>
  182  VSS78  POWER  = GND
  183  DQ23_A  BI  = M_G_CPU1_SA_DQ<23>
  184  VSS79  POWER  = GND
  185  DQ26_A  BI  = M_G_CPU1_SA_DQ<26>
  186  VSS80  POWER  = GND
  187  DQ27_A  BI  = M_G_CPU1_SA_DQ<27>
  188  VSS81  POWER  = GND
  189  \dqs8_a_c||tdqs8_a_c\  BI  = M_G_CPU1_SA_DQS_DN<8>
  190  \dqs8_a_t||tdqs8_a_t\  BI  = M_G_CPU1_SA_DQS_DP<8>
  191  VSS82  POWER  = GND
  192  DQ30_A  BI  = M_G_CPU1_SA_DQ<30>
  193  VSS83  POWER  = GND
  194  DQ31_A  BI  = M_G_CPU1_SA_DQ<31>
  195  VSS84  POWER  = GND
  196  CB2_A  BI  = M_G_CPU1_SA_CB<2>
  197  VSS85  POWER  = GND
  198  CB3_A  BI  = M_G_CPU1_SA_CB<3>
  199  VSS86  POWER  = GND
  200  \dqs9_a_c||tdqs9_a_c\  BI  = M_G_CPU1_SA_DQS_DN<9>
  201  \dqs9_a_t||tdqs9_a_t\  BI  = M_G_CPU1_SA_DQS_DP<9>
  202  VSS87  POWER  = GND
  203  CB6_A  BI  = M_G_CPU1_SA_CB<6>
  204  VSS88  POWER  = GND
  205  CB7_A  BI  = M_G_CPU1_SA_CB<7>
  206  VSS89  POWER  = GND
  207  RESET_N  IN  = RST_M_GH_CPU1_FPGA_N
  208  VSS90  POWER  = GND
  209  CS1_A_N  IN  = M_G_CPU1_SA_CS_N<3>
  210  VSS91  POWER  = GND
  211  CA1_A  IN  = M_G_CPU1_SA_CA<1>
  212  VSS92  POWER  = GND
  213  CA3_A  IN  = M_G_CPU1_SA_CA<3>
  214  VSS93  POWER  = GND
  215  CA5_A  IN  = M_G_CPU1_SA_CA<5>
  216  VSS94  POWER  = GND
  217  CK_T  IN  = M_G_CPU1_CLK_DP<1>
  218  CK_C  IN  = M_G_CPU1_CLK_DN<1>
  219  VSS95  POWER  = GND
  220  RFU4  TRI  = TP_CHG_CPU1_DIMM2_FRU_4
  221  CA1_B  IN  = M_G_CPU1_SB_CA<1>
  222  VSS96  POWER  = GND
  223  CA3_B  IN  = M_G_CPU1_SB_CA<3>
  224  VSS97  POWER  = GND
  225  CA5_B  IN  = M_G_CPU1_SB_CA<5>
  226  VSS98  POWER  = GND
  227  PAR_B  IN  = M_G_CPU1_SB_PAR
  228  VSS99  POWER  = GND
  229  CS1_B_N  IN  = M_G_CPU1_SB_CS_N<3>
  230  VSS100  POWER  = GND
  231  RFU5  TRI  = TP_CHG_CPU1_DIMM2_FRU_5
  232  RFU6  TRI  = TP_CHG_CPU1_DIMM2_FRU_6
  233  VSS101  POWER  = GND
  234  CB6_B  BI  = M_G_CPU1_SB_CB<6>
  235  VSS102  POWER  = GND
  236  CB7_B  BI  = M_G_CPU1_SB_CB<7>
  237  VSS103  POWER  = GND
  238  DQS4_B_C  BI  = M_G_CPU1_SB_DQS_DN<4>
  239  DQS4_B_T  BI  = M_G_CPU1_SB_DQS_DP<4>
  240  VSS104  POWER  = GND
  241  CB2_B  BI  = M_G_CPU1_SB_CB<2>
  242  VSS105  POWER  = GND
  243  CB3_B  BI  = M_G_CPU1_SB_CB<3>
  244  VSS106  POWER  = GND
  245  DQ2_B  BI  = M_G_CPU1_SB_DQ<2>
  246  VSS107  POWER  = GND
  247  DQ3_B  BI  = M_G_CPU1_SB_DQ<3>
  248  VSS108  POWER  = GND
  249  \dqs5_b_c||tdqs5_b_c\  BI  = M_G_CPU1_SB_DQS_DN<5>
  250  \dqs5_b_t||tdqs5_b_t\  BI  = M_G_CPU1_SB_DQS_DP<5>
  251  VSS109  POWER  = GND
  252  DQ6_B  BI  = M_G_CPU1_SB_DQ<6>
  253  VSS110  POWER  = GND
  254  DQ7_B  BI  = M_G_CPU1_SB_DQ<7>
  255  VSS111  POWER  = GND
  256  DQ10_B  BI  = M_G_CPU1_SB_DQ<10>
  257  VSS112  POWER  = GND
  258  DQ11_B  BI  = M_G_CPU1_SB_DQ<11>
  259  VSS113  POWER  = GND
  260  \dqs6_b_c||tdqs6_b_c\  BI  = M_G_CPU1_SB_DQS_DN<6>
  261  \dqs6_b_t||tdqs6_b_t\  BI  = M_G_CPU1_SB_DQS_DP<6>
  262  VSS114  POWER  = GND
  263  DQ14_B  BI  = M_G_CPU1_SB_DQ<14>
  264  VSS115  POWER  = GND
  265  DQ15_B  BI  = M_G_CPU1_SB_DQ<15>
  266  VSS116  POWER  = GND
  267  DQ18_B  BI  = M_G_CPU1_SB_DQ<18>
  268  VSS117  POWER  = GND
  269  DQ19_B  BI  = M_G_CPU1_SB_DQ<19>
  270  VSS118  POWER  = GND
  271  \dqs7_b_c||tdqs7_b_c\  BI  = M_G_CPU1_SB_DQS_DN<7>
  272  \dqs7_b_t||tdqs7_b_t\  BI  = M_G_CPU1_SB_DQS_DP<7>
  273  VSS119  POWER  = GND
  274  DQ22_B  BI  = M_G_CPU1_SB_DQ<22>
  275  VSS120  POWER  = GND
  276  DQ23_B  BI  = M_G_CPU1_SB_DQ<23>
  277  VSS121  POWER  = GND
  278  DQ26_B  BI  = M_G_CPU1_SB_DQ<26>
  279  VSS122  POWER  = GND
  280  DQ27_B  BI  = M_G_CPU1_SB_DQ<27>
  281  VSS123  POWER  = GND
  282  \dqs8_b_c||tdqs8_b_c\  BI  = M_G_CPU1_SB_DQS_DN<8>
  283  \dqs8_b_t||tdqs8_b_t\  BI  = M_G_CPU1_SB_DQS_DP<8>
  284  VSS124  POWER  = GND
  285  DQ30_B  BI  = M_G_CPU1_SB_DQ<30>
  286  VSS125  POWER  = GND
  287  DQ31_B  BI  = M_G_CPU1_SB_DQ<31>
  288  VSS126  POWER  = GND
  G1  G1  POWER  = GND
  G2  G2  POWER  = GND
  G3  G3  POWER  = GND
